(kicad_pcb
	(version 20241229)
	(generator "pcbnew")
	(generator_version "9.0")
	(general
		(thickness 1.6296)
		(legacy_teardrops no)
	)
	(paper "A3")
	(title_block
		(title "Thunderbolt to 10GbE adapter")
		(date "2026-04-21")
		(rev "1.1.0")
		(company "Antmicro Ltd")
		(comment 1 "www.antmicro.com")
		(comment 9 "footprints 546-550 of 703")
	)
	(layers
		(0 "F.Cu" signal)
		(4 "In1.Cu" signal)
		(6 "In2.Cu" signal)
		(8 "In3.Cu" signal)
		(10 "In4.Cu" signal)
		(12 "In5.Cu" signal)
		(14 "In6.Cu" signal)
		(2 "B.Cu" signal)
		(9 "F.Adhes" user "F.Adhesive")
		(11 "B.Adhes" user "B.Adhesive")
		(13 "F.Paste" user)
		(15 "B.Paste" user)
		(5 "F.SilkS" user "F.Silkscreen")
		(7 "B.SilkS" user "B.Silkscreen")
		(1 "F.Mask" user)
		(3 "B.Mask" user)
		(17 "Dwgs.User" user "User.Drawings")
		(19 "Cmts.User" user "User.Comments")
		(21 "Eco1.User" user "User.Eco1")
		(23 "Eco2.User" user "User.Eco2")
		(25 "Edge.Cuts" user)
		(27 "Margin" user)
		(31 "F.CrtYd" user "F.Courtyard")
		(29 "B.CrtYd" user "B.Courtyard")
		(35 "F.Fab" user)
		(33 "B.Fab" user)
	)
	(footprint "antmicro-footprints:C_0402_1005Metric"
		(layer "B.Cu")
		(at 130.45 120.049999 -90)
		(descr "Capacitor SMD 0402")
		(tags "capacitor SMD 0402")
		(property "Reference" "C67"
			(at -7.700002 -21.900002 90)
			(layer "B.SilkS")
			(effects
				(font
					(size 0.7 0.7)
					(thickness 0.15)
				)
				(justify mirror)
			)
		)
		(property "Value" "C_1u_0402"
			(at -1.022927 -2.155213 90)
			(layer "B.Fab")
			(effects
				(font
					(size 0.7 0.7)
					(thickness 0.15)
				)
				(justify left bottom mirror)
			)
		)
		(property "Datasheet" "https://product.tdk.com/en/search/capacitor/ceramic/mlcc/info?part_no=C1005X6S1A105K050BC"
			(at 0 0 90)
			(layer "B.Fab")
			(hide yes)
			(effects
				(font
					(size 1.27 1.27)
					(thickness 0.15)
				)
				(justify mirror)
			)
		)
		(property "Description" "SMD Multilayer Ceramic Capacitor, 1 µF, 10 V, 0402 [1005 Metric], ± 10%, X6S, C"
			(at 0 0 90)
			(layer "B.Fab")
			(hide yes)
			(effects
				(font
					(size 1.27 1.27)
					(thickness 0.15)
				)
				(justify mirror)
			)
		)
		(property "MPN" "C1005X6S1A105K050BC"
			(at 0 0 270)
			(unlocked yes)
			(layer "B.Fab")
			(hide yes)
			(effects
				(font
					(size 1 1)
					(thickness 0.15)
				)
				(justify mirror)
			)
		)
		(property "Manufacturer" "TDK"
			(at 0 0 270)
			(unlocked yes)
			(layer "B.Fab")
			(hide yes)
			(effects
				(font
					(size 1 1)
					(thickness 0.15)
				)
				(justify mirror)
			)
		)
		(property "License" "Apache-2.0"
			(at 0 0 270)
			(unlocked yes)
			(layer "B.Fab")
			(hide yes)
			(effects
				(font
					(size 1 1)
					(thickness 0.15)
				)
				(justify mirror)
			)
		)
		(property "Val" "1u"
			(at 0 0 270)
			(unlocked yes)
			(layer "B.Fab")
			(hide yes)
			(effects
				(font
					(size 1 1)
					(thickness 0.15)
				)
				(justify mirror)
			)
		)
		(property "Voltage" ""
			(at 0 0 270)
			(unlocked yes)
			(layer "B.Fab")
			(hide yes)
			(effects
				(font
					(size 1 1)
					(thickness 0.15)
				)
				(justify mirror)
			)
		)
		(property "Dielectric" ""
			(at 0 0 270)
			(unlocked yes)
			(layer "B.Fab")
			(hide yes)
			(effects
				(font
					(size 1 1)
					(thickness 0.15)
				)
				(justify mirror)
			)
		)
		(property "Author" "Antmicro"
			(at 0 0 270)
			(unlocked yes)
			(layer "B.Fab")
			(hide yes)
			(effects
				(font
					(size 1 1)
					(thickness 0.15)
				)
				(justify mirror)
			)
		)
		(sheetname "/TB Controller - Power/")
		(sheetfile "tb-power.kicad_sch")
		(attr smd)
		(fp_rect
			(start -0.925 0.47)
			(end 0.925 -0.47)
			(stroke
				(width 0.05)
				(type default)
			)
			(fill no)
			(layer "B.CrtYd")
		)
		(fp_line
			(start -0.494 0.25)
			(end 0.504 0.25)
			(stroke
				(width 0.15)
				(type solid)
			)
			(layer "B.Fab")
		)
		(fp_line
			(start 0.504 0.25)
			(end 0.504 -0.248)
			(stroke
				(width 0.15)
				(type solid)
			)
			(layer "B.Fab")
		)
		(fp_line
			(start -0.494 -0.248)
			(end -0.494 0.25)
			(stroke
				(width 0.15)
				(type solid)
			)
			(layer "B.Fab")
		)
		(fp_line
			(start 0.504 -0.248)
			(end -0.494 -0.248)
			(stroke
				(width 0.15)
				(type solid)
			)
			(layer "B.Fab")
		)
		(fp_text user "${REFERENCE}"
			(at -0.939 -4.599 90)
			(layer "B.Fab")
			(effects
				(font
					(size 0.7 0.7)
					(thickness 0.15)
				)
				(justify left bottom mirror)
			)
		)
		(fp_text user "Author: Antmicro"
			(at -0.939 -3.399 90)
			(layer "B.Fab")
			(effects
				(font
					(size 0.7 0.7)
					(thickness 0.15)
				)
				(justify left bottom mirror)
			)
		)
		(fp_text user "License: Apache-2.0"
			(at -0.939 -5.799 90)
			(layer "B.Fab")
			(effects
				(font
					(size 0.7 0.7)
					(thickness 0.15)
				)
				(justify left bottom mirror)
			)
		)
		(pad "1" smd roundrect
			(at -0.48 0 270)
			(size 0.59 0.64)
			(layers "B.Cu" "B.Mask" "B.Paste")
			(roundrect_rratio 0.25)
			(net 23 "GND")
			(pintype "passive")
		)
		(pad "2" smd roundrect
			(at 0.48 0 270)
			(size 0.59 0.64)
			(layers "B.Cu" "B.Mask" "B.Paste")
			(roundrect_rratio 0.25)
			(net 404 "Net-(C58-Pad2)")
			(pintype "passive")
		)
	)
	(footprint "antmicro-footprints:C_0402_1005Metric"
		(layer "B.Cu")
		(at 149.331866 76.260117 180)
		(descr "Capacitor SMD 0402")
		(tags "capacitor SMD 0402")
		(property "Reference" "C230"
			(at -19.468135 -9.464883 0)
			(layer "B.SilkS")
			(effects
				(font
					(size 0.7 0.7)
					(thickness 0.15)
				)
				(justify mirror)
			)
		)
		(property "Value" "C_1u_25V_0402"
			(at -1.022927 -2.155213 0)
			(layer "B.Fab")
			(effects
				(font
					(size 0.7 0.7)
					(thickness 0.15)
				)
				(justify left bottom mirror)
			)
		)
		(property "Datasheet" "https://www.murata.com/products/productdetail?partno=GRM155R61E105KE11%23"
			(at 0 0 0)
			(layer "B.Fab")
			(hide yes)
			(effects
				(font
					(size 1.27 1.27)
					(thickness 0.15)
				)
				(justify mirror)
			)
		)
		(property "Description" "SMD Multilayer Ceramic Capacitor, 1 µF, 25 V, 0402 [1005 Metric], ± 10%, X5R, GRM Series"
			(at 0 0 0)
			(layer "B.Fab")
			(hide yes)
			(effects
				(font
					(size 1.27 1.27)
					(thickness 0.15)
				)
				(justify mirror)
			)
		)
		(property "MPN" "GRM155R61E105KE11J"
			(at 0 0 180)
			(unlocked yes)
			(layer "B.Fab")
			(hide yes)
			(effects
				(font
					(size 1 1)
					(thickness 0.15)
				)
				(justify mirror)
			)
		)
		(property "Manufacturer" "Murata"
			(at 0 0 180)
			(unlocked yes)
			(layer "B.Fab")
			(hide yes)
			(effects
				(font
					(size 1 1)
					(thickness 0.15)
				)
				(justify mirror)
			)
		)
		(property "License" "Apache-2.0"
			(at 0 0 180)
			(unlocked yes)
			(layer "B.Fab")
			(hide yes)
			(effects
				(font
					(size 1 1)
					(thickness 0.15)
				)
				(justify mirror)
			)
		)
		(property "Author" "Antmicro"
			(at 0 0 180)
			(unlocked yes)
			(layer "B.Fab")
			(hide yes)
			(effects
				(font
					(size 1 1)
					(thickness 0.15)
				)
				(justify mirror)
			)
		)
		(property "Val" "1u"
			(at 0 0 180)
			(unlocked yes)
			(layer "B.Fab")
			(hide yes)
			(effects
				(font
					(size 1 1)
					(thickness 0.15)
				)
				(justify mirror)
			)
		)
		(property "Voltage" "25V"
			(at 0 0 180)
			(unlocked yes)
			(layer "B.Fab")
			(hide yes)
			(effects
				(font
					(size 1 1)
					(thickness 0.15)
				)
				(justify mirror)
			)
		)
		(property "Dielectric" "X5R"
			(at 0 0 180)
			(unlocked yes)
			(layer "B.Fab")
			(hide yes)
			(effects
				(font
					(size 1 1)
					(thickness 0.15)
				)
				(justify mirror)
			)
		)
		(sheetname "/X710-AT2 power/")
		(sheetfile "x710-at2-power.kicad_sch")
		(attr smd)
		(fp_rect
			(start -0.925 0.47)
			(end 0.925 -0.47)
			(stroke
				(width 0.05)
				(type default)
			)
			(fill no)
			(layer "B.CrtYd")
		)
		(fp_line
			(start 0.504 0.25)
			(end 0.504 -0.248)
			(stroke
				(width 0.15)
				(type solid)
			)
			(layer "B.Fab")
		)
		(fp_line
			(start 0.504 -0.248)
			(end -0.494 -0.248)
			(stroke
				(width 0.15)
				(type solid)
			)
			(layer "B.Fab")
		)
		(fp_line
			(start -0.494 0.25)
			(end 0.504 0.25)
			(stroke
				(width 0.15)
				(type solid)
			)
			(layer "B.Fab")
		)
		(fp_line
			(start -0.494 -0.248)
			(end -0.494 0.25)
			(stroke
				(width 0.15)
				(type solid)
			)
			(layer "B.Fab")
		)
		(fp_text user "Author: Antmicro"
			(at -0.939 -3.399 0)
			(layer "B.Fab")
			(effects
				(font
					(size 0.7 0.7)
					(thickness 0.15)
				)
				(justify left bottom mirror)
			)
		)
		(fp_text user "License: Apache-2.0"
			(at -0.939 -5.799 0)
			(layer "B.Fab")
			(effects
				(font
					(size 0.7 0.7)
					(thickness 0.15)
				)
				(justify left bottom mirror)
			)
		)
		(fp_text user "${REFERENCE}"
			(at -0.939 -4.599 0)
			(layer "B.Fab")
			(effects
				(font
					(size 0.7 0.7)
					(thickness 0.15)
				)
				(justify left bottom mirror)
			)
		)
		(pad "1" smd roundrect
			(at -0.48 0 180)
			(size 0.59 0.64)
			(layers "B.Cu" "B.Mask" "B.Paste")
			(roundrect_rratio 0.25)
			(net 23 "GND")
			(pintype "passive")
		)
		(pad "2" smd roundrect
			(at 0.48 0 180)
			(size 0.59 0.64)
			(layers "B.Cu" "B.Mask" "B.Paste")
			(roundrect_rratio 0.25)
			(net 7 "+3V3")
			(pintype "passive")
		)
	)
	(footprint "antmicro-footprints:C_0402_1005Metric"
		(layer "B.Cu")
		(at 124.599999 122.475001)
		(descr "Capacitor SMD 0402")
		(tags "capacitor SMD 0402")
		(property "Reference" "C71"
			(at 21.900002 -7.700002 180)
			(layer "B.SilkS")
			(effects
				(font
					(size 0.7 0.7)
					(thickness 0.15)
				)
				(justify mirror)
			)
		)
		(property "Value" "C_1u_0402"
			(at -1.022927 -2.155213 180)
			(layer "B.Fab")
			(effects
				(font
					(size 0.7 0.7)
					(thickness 0.15)
				)
				(justify left bottom mirror)
			)
		)
		(property "Datasheet" "https://product.tdk.com/en/search/capacitor/ceramic/mlcc/info?part_no=C1005X6S1A105K050BC"
			(at 0 0 180)
			(layer "B.Fab")
			(hide yes)
			(effects
				(font
					(size 1.27 1.27)
					(thickness 0.15)
				)
				(justify mirror)
			)
		)
		(property "Description" "SMD Multilayer Ceramic Capacitor, 1 µF, 10 V, 0402 [1005 Metric], ± 10%, X6S, C"
			(at 0 0 180)
			(layer "B.Fab")
			(hide yes)
			(effects
				(font
					(size 1.27 1.27)
					(thickness 0.15)
				)
				(justify mirror)
			)
		)
		(property "MPN" "C1005X6S1A105K050BC"
			(at 0 0 0)
			(unlocked yes)
			(layer "B.Fab")
			(hide yes)
			(effects
				(font
					(size 1 1)
					(thickness 0.15)
				)
				(justify mirror)
			)
		)
		(property "Manufacturer" "TDK"
			(at 0 0 0)
			(unlocked yes)
			(layer "B.Fab")
			(hide yes)
			(effects
				(font
					(size 1 1)
					(thickness 0.15)
				)
				(justify mirror)
			)
		)
		(property "License" "Apache-2.0"
			(at 0 0 0)
			(unlocked yes)
			(layer "B.Fab")
			(hide yes)
			(effects
				(font
					(size 1 1)
					(thickness 0.15)
				)
				(justify mirror)
			)
		)
		(property "Val" "1u"
			(at 0 0 0)
			(unlocked yes)
			(layer "B.Fab")
			(hide yes)
			(effects
				(font
					(size 1 1)
					(thickness 0.15)
				)
				(justify mirror)
			)
		)
		(property "Voltage" ""
			(at 0 0 0)
			(unlocked yes)
			(layer "B.Fab")
			(hide yes)
			(effects
				(font
					(size 1 1)
					(thickness 0.15)
				)
				(justify mirror)
			)
		)
		(property "Dielectric" ""
			(at 0 0 0)
			(unlocked yes)
			(layer "B.Fab")
			(hide yes)
			(effects
				(font
					(size 1 1)
					(thickness 0.15)
				)
				(justify mirror)
			)
		)
		(property "Author" "Antmicro"
			(at 0 0 0)
			(unlocked yes)
			(layer "B.Fab")
			(hide yes)
			(effects
				(font
					(size 1 1)
					(thickness 0.15)
				)
				(justify mirror)
			)
		)
		(sheetname "/TB Controller - Power/")
		(sheetfile "tb-power.kicad_sch")
		(attr smd)
		(fp_rect
			(start -0.925 0.47)
			(end 0.925 -0.47)
			(stroke
				(width 0.05)
				(type default)
			)
			(fill no)
			(layer "B.CrtYd")
		)
		(fp_line
			(start -0.494 -0.248)
			(end -0.494 0.25)
			(stroke
				(width 0.15)
				(type solid)
			)
			(layer "B.Fab")
		)
		(fp_line
			(start -0.494 0.25)
			(end 0.504 0.25)
			(stroke
				(width 0.15)
				(type solid)
			)
			(layer "B.Fab")
		)
		(fp_line
			(start 0.504 -0.248)
			(end -0.494 -0.248)
			(stroke
				(width 0.15)
				(type solid)
			)
			(layer "B.Fab")
		)
		(fp_line
			(start 0.504 0.25)
			(end 0.504 -0.248)
			(stroke
				(width 0.15)
				(type solid)
			)
			(layer "B.Fab")
		)
		(fp_text user "Author: Antmicro"
			(at -0.939 -3.399 180)
			(layer "B.Fab")
			(effects
				(font
					(size 0.7 0.7)
					(thickness 0.15)
				)
				(justify left bottom mirror)
			)
		)
		(fp_text user "${REFERENCE}"
			(at -0.939 -4.599 180)
			(layer "B.Fab")
			(effects
				(font
					(size 0.7 0.7)
					(thickness 0.15)
				)
				(justify left bottom mirror)
			)
		)
		(fp_text user "License: Apache-2.0"
			(at -0.939 -5.799 180)
			(layer "B.Fab")
			(effects
				(font
					(size 0.7 0.7)
					(thickness 0.15)
				)
				(justify left bottom mirror)
			)
		)
		(pad "1" smd roundrect
			(at -0.48 0)
			(size 0.59 0.64)
			(layers "B.Cu" "B.Mask" "B.Paste")
			(roundrect_rratio 0.25)
			(net 23 "GND")
			(pintype "passive")
		)
		(pad "2" smd roundrect
			(at 0.48 0)
			(size 0.59 0.64)
			(layers "B.Cu" "B.Mask" "B.Paste")
			(roundrect_rratio 0.25)
			(net 405 "Net-(C66-Pad2)")
			(pintype "passive")
		)
	)
	(footprint "antmicro-footprints:R_0402_1005Metric"
		(layer "B.Cu")
		(at 162.991867 69.5 -90)
		(descr "Resistor SMD 0402")
		(tags "resistor SMD 0402")
		(property "Reference" "R141"
			(at 2.25 0 90)
			(layer "B.SilkS")
			(effects
				(font
					(size 0.7 0.7)
					(thickness 0.15)
				)
				(justify mirror)
			)
		)
		(property "Value" "R_100R_0402"
			(at -1.011843 -1.772047 90)
			(layer "B.Fab")
			(effects
				(font
					(size 0.7 0.7)
					(thickness 0.15)
				)
				(justify left bottom mirror)
			)
		)
		(property "Datasheet" "https://www.bourns.com/docs/product-datasheets/cr.pdf"
			(at 0 0 90)
			(layer "B.Fab")
			(hide yes)
			(effects
				(font
					(size 1.27 1.27)
					(thickness 0.15)
				)
				(justify mirror)
			)
		)
		(property "Description" "SMD Chip Resistor, 100 ohm, ± 1%, 62.5 mW, 0402 [1005 Metric], Thick Film, General Purpose"
			(at 0 0 90)
			(layer "B.Fab")
			(hide yes)
			(effects
				(font
					(size 1.27 1.27)
					(thickness 0.15)
				)
				(justify mirror)
			)
		)
		(property "MPN" "CR0402-FX-1000GLF"
			(at 0 0 270)
			(unlocked yes)
			(layer "B.Fab")
			(hide yes)
			(effects
				(font
					(size 1 1)
					(thickness 0.15)
				)
				(justify mirror)
			)
		)
		(property "Manufacturer" "Bourns"
			(at 0 0 270)
			(unlocked yes)
			(layer "B.Fab")
			(hide yes)
			(effects
				(font
					(size 1 1)
					(thickness 0.15)
				)
				(justify mirror)
			)
		)
		(property "License" "Apache-2.0"
			(at 0 0 270)
			(unlocked yes)
			(layer "B.Fab")
			(hide yes)
			(effects
				(font
					(size 1 1)
					(thickness 0.15)
				)
				(justify mirror)
			)
		)
		(property "Author" "Antmicro"
			(at 0 0 270)
			(unlocked yes)
			(layer "B.Fab")
			(hide yes)
			(effects
				(font
					(size 1 1)
					(thickness 0.15)
				)
				(justify mirror)
			)
		)
		(property "Val" "100R"
			(at 0 0 270)
			(unlocked yes)
			(layer "B.Fab")
			(hide yes)
			(effects
				(font
					(size 1 1)
					(thickness 0.15)
				)
				(justify mirror)
			)
		)
		(property "Tolerance" "1%"
			(at 0 0 270)
			(unlocked yes)
			(layer "B.Fab")
			(hide yes)
			(effects
				(font
					(size 1 1)
					(thickness 0.15)
				)
				(justify mirror)
			)
		)
		(sheetname "/X710-AT2 Misc/")
		(sheetfile "x710-at2-mics.kicad_sch")
		(attr smd)
		(fp_rect
			(start -0.925 0.47)
			(end 0.925 -0.47)
			(stroke
				(width 0.05)
				(type default)
			)
			(fill no)
			(layer "B.CrtYd")
		)
		(fp_rect
			(start -0.5 0.25)
			(end 0.5 -0.25)
			(stroke
				(width 0.15)
				(type solid)
			)
			(fill no)
			(layer "B.Fab")
		)
		(fp_text user "${REFERENCE}"
			(at -0.95 -3.168 90)
			(layer "B.Fab")
			(effects
				(font
					(size 0.7 0.7)
					(thickness 0.15)
				)
				(justify left bottom mirror)
			)
		)
		(fp_text user "License: Apache-2.0"
			(at -0.95 -5.169 90)
			(layer "B.Fab")
			(effects
				(font
					(size 0.7 0.7)
					(thickness 0.15)
				)
				(justify left bottom mirror)
			)
		)
		(fp_text user "Author: Antmicro"
			(at -0.95 -4.169 90)
			(layer "B.Fab")
			(effects
				(font
					(size 0.7 0.7)
					(thickness 0.15)
				)
				(justify left bottom mirror)
			)
		)
		(pad "1" smd roundrect
			(at -0.48 0 270)
			(size 0.59 0.64)
			(layers "B.Cu" "B.Mask" "B.Paste")
			(roundrect_rratio 0.25)
			(net 439 "Net-(U17-A_{2})")
			(pintype "passive")
		)
		(pad "2" smd roundrect
			(at 0.48 0 270)
			(size 0.59 0.64)
			(layers "B.Cu" "B.Mask" "B.Paste")
			(roundrect_rratio 0.25)
			(net 23 "GND")
			(pintype "passive")
		)
	)
	(footprint "antmicro-footprints:R_0402_1005Metric"
		(layer "B.Cu")
		(at 157.131866 70.035117 -90)
		(descr "Resistor SMD 0402")
		(tags "resistor SMD 0402")
		(property "Reference" "R167"
			(at 9.464883 -19.468134 90)
			(layer "B.SilkS")
			(effects
				(font
					(size 0.7 0.7)
					(thickness 0.15)
				)
				(justify mirror)
			)
		)
		(property "Value" "R_22R_0402"
			(at -1.011843 -1.772047 90)
			(layer "B.Fab")
			(effects
				(font
					(size 0.7 0.7)
					(thickness 0.15)
				)
				(justify left bottom mirror)
			)
		)
		(property "Datasheet" "https://www.bourns.com/docs/product-datasheets/cr.pdf"
			(at 0 0 90)
			(layer "B.Fab")
			(hide yes)
			(effects
				(font
					(size 1.27 1.27)
					(thickness 0.15)
				)
				(justify mirror)
			)
		)
		(property "Description" "SMD Chip Resistor, 22 ohm, ± 1%, 62.5 mW, 0402 [1005 Metric], Thick Film, General Purpose"
			(at 0 0 90)
			(layer "B.Fab")
			(hide yes)
			(effects
				(font
					(size 1.27 1.27)
					(thickness 0.15)
				)
				(justify mirror)
			)
		)
		(property "MPN" "CR0402-FX-22R0GLF"
			(at 0 0 270)
			(unlocked yes)
			(layer "B.Fab")
			(hide yes)
			(effects
				(font
					(size 1 1)
					(thickness 0.15)
				)
				(justify mirror)
			)
		)
		(property "Manufacturer" "Bourns"
			(at 0 0 270)
			(unlocked yes)
			(layer "B.Fab")
			(hide yes)
			(effects
				(font
					(size 1 1)
					(thickness 0.15)
				)
				(justify mirror)
			)
		)
		(property "License" "Apache-2.0"
			(at 0 0 270)
			(unlocked yes)
			(layer "B.Fab")
			(hide yes)
			(effects
				(font
					(size 1 1)
					(thickness 0.15)
				)
				(justify mirror)
			)
		)
		(property "Author" "Antmicro"
			(at 0 0 270)
			(unlocked yes)
			(layer "B.Fab")
			(hide yes)
			(effects
				(font
					(size 1 1)
					(thickness 0.15)
				)
				(justify mirror)
			)
		)
		(property "Val" "22R"
			(at 0 0 270)
			(unlocked yes)
			(layer "B.Fab")
			(hide yes)
			(effects
				(font
					(size 1 1)
					(thickness 0.15)
				)
				(justify mirror)
			)
		)
		(property "Tolerance" "1%"
			(at 0 0 270)
			(unlocked yes)
			(layer "B.Fab")
			(hide yes)
			(effects
				(font
					(size 1 1)
					(thickness 0.15)
				)
				(justify mirror)
			)
		)
		(sheetname "/X710-AT2 Misc/")
		(sheetfile "x710-at2-mics.kicad_sch")
		(attr smd)
		(fp_rect
			(start -0.925 0.47)
			(end 0.925 -0.47)
			(stroke
				(width 0.05)
				(type default)
			)
			(fill no)
			(layer "B.CrtYd")
		)
		(fp_rect
			(start -0.5 0.25)
			(end 0.5 -0.25)
			(stroke
				(width 0.15)
				(type solid)
			)
			(fill no)
			(layer "B.Fab")
		)
		(fp_text user "${REFERENCE}"
			(at -0.95 -3.168 90)
			(layer "B.Fab")
			(effects
				(font
					(size 0.7 0.7)
					(thickness 0.15)
				)
				(justify left bottom mirror)
			)
		)
		(fp_text user "Author: Antmicro"
			(at -0.95 -4.169 90)
			(layer "B.Fab")
			(effects
				(font
					(size 0.7 0.7)
					(thickness 0.15)
				)
				(justify left bottom mirror)
			)
		)
		(fp_text user "License: Apache-2.0"
			(at -0.95 -5.169 90)
			(layer "B.Fab")
			(effects
				(font
					(size 0.7 0.7)
					(thickness 0.15)
				)
				(justify left bottom mirror)
			)
		)
		(pad "1" smd roundrect
			(at -0.48 0 270)
			(size 0.59 0.64)
			(layers "B.Cu" "B.Mask" "B.Paste")
			(roundrect_rratio 0.25)
			(net 142 "/X710-AT2 Misc/NCSI.CRS_DV")
			(pintype "passive")
		)
		(pad "2" smd roundrect
			(at 0.48 0 270)
			(size 0.59 0.64)
			(layers "B.Cu" "B.Mask" "B.Paste")
			(roundrect_rratio 0.25)
			(net 441 "Net-(U14D-NCSI_CRS_DV)")
			(pintype "passive")
		)
	)
)
